(kicad_pcb
	(version 20260206)
	(generator "pcbnew")
	(generator_version "10.0")
	(general
		(thickness 1.6)
		(legacy_teardrops no)
	)
	(paper "A4")
	(title_block
		(title "04192023_DAF0TMB3IC0_F0TG_MB_C_brd_V02_OCP.brd")
		(comment 1 "Grand Teton / footprints 8076-8082 of 8354")
	)
	(layers
		(0 "F.Cu" signal "TOP")
		(4 "In1.Cu" signal "GND")
		(6 "In2.Cu" signal "IN1")
		(8 "In3.Cu" signal "GND1")
		(10 "In4.Cu" signal "IN2")
		(12 "In5.Cu" signal "GND2")
		(14 "In6.Cu" signal "IN3")
		(16 "In7.Cu" signal "GND3")
		(18 "In8.Cu" signal "VCC")
		(20 "In9.Cu" signal "VCC1")
		(22 "In10.Cu" signal "GND4")
		(24 "In11.Cu" signal "IN4")
		(26 "In12.Cu" signal "GND5")
		(28 "In13.Cu" signal "IN5")
		(30 "In14.Cu" signal "GND6")
		(32 "In15.Cu" signal "IN6")
		(34 "In16.Cu" signal "GND7")
		(2 "B.Cu" signal "BOTTOM")
		(9 "F.Adhes" user "F.Adhesive")
		(11 "B.Adhes" user "B.Adhesive")
		(13 "F.Paste" user "Package Geometry/Pastemask Top")
		(15 "B.Paste" user "Package Geometry/Pastemask Bottom")
		(5 "F.SilkS" user "Ref Des/Silkscreen Top")
		(7 "B.SilkS" user "Ref Des/Silkscreen Bottom")
		(1 "F.Mask" user "Board Geometry/Soldermask Top")
		(3 "B.Mask" user "Board Geometry/Soldermask Bottom")
		(17 "Dwgs.User" user "User.Drawings")
		(19 "Cmts.User" user "User.Comments")
		(21 "Eco1.User" user "User.Eco1")
		(23 "Eco2.User" user "User.Eco2")
		(25 "Edge.Cuts" user "Board Geometry/Outline")
		(27 "Margin" user)
		(31 "F.CrtYd" user "Package Geometry/Place Bound Top")
		(29 "B.CrtYd" user "Package Geometry/Place Bound Bottom")
		(35 "F.Fab" user "Ref Des/Assembly Top")
		(33 "B.Fab" user "Ref Des/Assembly Bottom")
	)
	(footprint ""
		(layer "B.Cu")
		(at 402.322538 -320.189352 180)
		(property "Reference" "R447"
			(at 0 0 0)
			(layer "B.SilkS")
			(hide yes)
			(effects
				(font
					(size 1.27 1.27)
				)
				(justify mirror)
			)
		)
		(property "Value" ""
			(at 0 0 0)
			(layer "B.Fab")
			(effects
				(font
					(size 1.27 1.27)
				)
				(justify mirror)
			)
		)
		(duplicate_pad_numbers_are_jumpers no)
		(fp_line
			(start 0.7874 0.4064)
			(end 0.7874 -0.4064)
			(stroke
				(width 0.1524)
				(type default)
			)
			(layer "B.SilkS")
		)
		(fp_line
			(start 0.7874 -0.4064)
			(end -0.7874 -0.4064)
			(stroke
				(width 0.1524)
				(type default)
			)
			(layer "B.SilkS")
		)
		(fp_line
			(start -0.7874 0.4064)
			(end 0.7874 0.4064)
			(stroke
				(width 0.1524)
				(type default)
			)
			(layer "B.SilkS")
		)
		(fp_line
			(start -0.7874 -0.4064)
			(end -0.7874 0.4064)
			(stroke
				(width 0.1524)
				(type default)
			)
			(layer "B.SilkS")
		)
		(fp_line
			(start 0.67945 0.3048)
			(end 0.67945 -0.305054)
			(stroke
				(width 0.1)
				(type default)
			)
			(layer "B.Fab")
		)
		(fp_line
			(start 0.67945 -0.305054)
			(end 0.12065 -0.305054)
			(stroke
				(width 0.1)
				(type default)
			)
			(layer "B.Fab")
		)
		(fp_line
			(start 0.12065 0.3048)
			(end 0.67945 0.3048)
			(stroke
				(width 0.1)
				(type default)
			)
			(layer "B.Fab")
		)
		(fp_line
			(start 0.12065 0.2794)
			(end 0.12065 0.3048)
			(stroke
				(width 0.1)
				(type default)
			)
			(layer "B.Fab")
		)
		(fp_line
			(start 0.12065 -0.2794)
			(end -0.12065 -0.2794)
			(stroke
				(width 0.1)
				(type default)
			)
			(layer "B.Fab")
		)
		(fp_line
			(start 0.12065 -0.305054)
			(end 0.12065 -0.2794)
			(stroke
				(width 0.1)
				(type default)
			)
			(layer "B.Fab")
		)
		(fp_line
			(start -0.120396 0.3048)
			(end -0.120396 0.2794)
			(stroke
				(width 0.1)
				(type default)
			)
			(layer "B.Fab")
		)
		(fp_line
			(start -0.120396 0.2794)
			(end 0.12065 0.2794)
			(stroke
				(width 0.1)
				(type default)
			)
			(layer "B.Fab")
		)
		(fp_line
			(start -0.12065 -0.2794)
			(end -0.12065 -0.3048)
			(stroke
				(width 0.1)
				(type default)
			)
			(layer "B.Fab")
		)
		(fp_line
			(start -0.12065 -0.3048)
			(end -0.67945 -0.3048)
			(stroke
				(width 0.1)
				(type default)
			)
			(layer "B.Fab")
		)
		(fp_line
			(start -0.67945 0.3048)
			(end -0.120396 0.3048)
			(stroke
				(width 0.1)
				(type default)
			)
			(layer "B.Fab")
		)
		(fp_line
			(start -0.67945 -0.3048)
			(end -0.67945 0.3048)
			(stroke
				(width 0.1)
				(type default)
			)
			(layer "B.Fab")
		)
		(pad "1" smd circle
			(at 0.40005 0)
			(size 0 0)
			(layers "B.Cu" "B.Mask" "B.Paste")
			(net "IRQ_TPM_SPI_R_N")
		)
		(pad "2" smd circle
			(at -0.40005 0)
			(size 0 0)
			(layers "B.Cu" "B.Mask" "B.Paste")
			(net "PVDD18_S5_P0")
		)
	)
	(footprint ""
		(layer "B.Cu")
		(at 20.480782 -410.564584 180)
		(property "Reference" "PR6811"
			(at 0 0 0)
			(layer "B.SilkS")
			(hide yes)
			(effects
				(font
					(size 1.27 1.27)
				)
				(justify mirror)
			)
		)
		(property "Value" ""
			(at 0 0 0)
			(layer "B.Fab")
			(effects
				(font
					(size 1.27 1.27)
				)
				(justify mirror)
			)
		)
		(duplicate_pad_numbers_are_jumpers no)
		(fp_line
			(start 0.7874 0.4064)
			(end 0.7874 -0.4064)
			(stroke
				(width 0.1524)
				(type default)
			)
			(layer "B.SilkS")
		)
		(fp_line
			(start 0.7874 -0.4064)
			(end -0.7874 -0.4064)
			(stroke
				(width 0.1524)
				(type default)
			)
			(layer "B.SilkS")
		)
		(fp_line
			(start -0.7874 0.4064)
			(end 0.7874 0.4064)
			(stroke
				(width 0.1524)
				(type default)
			)
			(layer "B.SilkS")
		)
		(fp_line
			(start -0.7874 -0.4064)
			(end -0.7874 0.4064)
			(stroke
				(width 0.1524)
				(type default)
			)
			(layer "B.SilkS")
		)
		(fp_line
			(start 0.67945 0.3048)
			(end 0.67945 -0.305054)
			(stroke
				(width 0.1)
				(type default)
			)
			(layer "B.Fab")
		)
		(fp_line
			(start 0.67945 -0.305054)
			(end 0.12065 -0.305054)
			(stroke
				(width 0.1)
				(type default)
			)
			(layer "B.Fab")
		)
		(fp_line
			(start 0.12065 0.3048)
			(end 0.67945 0.3048)
			(stroke
				(width 0.1)
				(type default)
			)
			(layer "B.Fab")
		)
		(fp_line
			(start 0.12065 0.2794)
			(end 0.12065 0.3048)
			(stroke
				(width 0.1)
				(type default)
			)
			(layer "B.Fab")
		)
		(fp_line
			(start 0.12065 -0.2794)
			(end -0.12065 -0.2794)
			(stroke
				(width 0.1)
				(type default)
			)
			(layer "B.Fab")
		)
		(fp_line
			(start 0.12065 -0.305054)
			(end 0.12065 -0.2794)
			(stroke
				(width 0.1)
				(type default)
			)
			(layer "B.Fab")
		)
		(fp_line
			(start -0.120396 0.3048)
			(end -0.120396 0.2794)
			(stroke
				(width 0.1)
				(type default)
			)
			(layer "B.Fab")
		)
		(fp_line
			(start -0.120396 0.2794)
			(end 0.12065 0.2794)
			(stroke
				(width 0.1)
				(type default)
			)
			(layer "B.Fab")
		)
		(fp_line
			(start -0.12065 -0.2794)
			(end -0.12065 -0.3048)
			(stroke
				(width 0.1)
				(type default)
			)
			(layer "B.Fab")
		)
		(fp_line
			(start -0.12065 -0.3048)
			(end -0.67945 -0.3048)
			(stroke
				(width 0.1)
				(type default)
			)
			(layer "B.Fab")
		)
		(fp_line
			(start -0.67945 0.3048)
			(end -0.120396 0.3048)
			(stroke
				(width 0.1)
				(type default)
			)
			(layer "B.Fab")
		)
		(fp_line
			(start -0.67945 -0.3048)
			(end -0.67945 0.3048)
			(stroke
				(width 0.1)
				(type default)
			)
			(layer "B.Fab")
		)
		(pad "1" smd circle
			(at 0.40005 0)
			(size 0 0)
			(layers "B.Cu" "B.Mask" "B.Paste")
			(net "P0V9_RETIMER_CPU1_SVID_CLK")
		)
		(pad "2" smd circle
			(at -0.40005 0)
			(size 0 0)
			(layers "B.Cu" "B.Mask" "B.Paste")
			(net "GND")
		)
	)
	(footprint ""
		(layer "B.Cu")
		(at 309.574184 -338.086446 -90)
		(property "Reference" "PC129_3"
			(at 0 0 90)
			(layer "B.SilkS")
			(hide yes)
			(effects
				(font
					(size 1.27 1.27)
				)
				(justify mirror)
			)
		)
		(property "Value" ""
			(at 0 0 90)
			(layer "B.Fab")
			(effects
				(font
					(size 1.27 1.27)
				)
				(justify mirror)
			)
		)
		(duplicate_pad_numbers_are_jumpers no)
		(fp_line
			(start -1.524 0.762)
			(end 1.524 0.762)
			(stroke
				(width 0.1524)
				(type default)
			)
			(layer "B.SilkS")
		)
		(fp_line
			(start 1.524 0.762)
			(end 1.524 -0.762)
			(stroke
				(width 0.1524)
				(type default)
			)
			(layer "B.SilkS")
		)
		(fp_line
			(start -1.524 -0.762)
			(end -1.524 0.762)
			(stroke
				(width 0.1524)
				(type default)
			)
			(layer "B.SilkS")
		)
		(fp_line
			(start 1.524 -0.762)
			(end -1.524 -0.762)
			(stroke
				(width 0.1524)
				(type default)
			)
			(layer "B.SilkS")
		)
		(fp_line
			(start -1.1049 0.724916)
			(end -1.1049 -0.724916)
			(stroke
				(width 0.1)
				(type default)
			)
			(layer "B.Fab")
		)
		(fp_line
			(start 1.1049 0.724916)
			(end -1.1049 0.724916)
			(stroke
				(width 0.1)
				(type default)
			)
			(layer "B.Fab")
		)
		(fp_line
			(start -1.1049 -0.724916)
			(end 1.1049 -0.724916)
			(stroke
				(width 0.1)
				(type default)
			)
			(layer "B.Fab")
		)
		(fp_line
			(start 1.1049 -0.724916)
			(end 1.1049 0.724916)
			(stroke
				(width 0.1)
				(type default)
			)
			(layer "B.Fab")
		)
		(pad "1" smd rect
			(at 0.889 0 270)
			(size 1.016 1.27)
			(layers "B.Cu" "B.Mask" "B.Paste")
			(net "PVDDCR_CPU1_P0")
		)
		(pad "2" smd rect
			(at -0.889 0 270)
			(size 1.016 1.27)
			(layers "B.Cu" "B.Mask" "B.Paste")
			(net "GND")
		)
	)
	(footprint ""
		(layer "B.Cu")
		(at 369.646454 -254.19431)
		(property "Reference" "C2586"
			(at 0 0 0)
			(layer "B.SilkS")
			(hide yes)
			(effects
				(font
					(size 1.27 1.27)
				)
				(justify mirror)
			)
		)
		(property "Value" ""
			(at 0 0 0)
			(layer "B.Fab")
			(effects
				(font
					(size 1.27 1.27)
				)
				(justify mirror)
			)
		)
		(duplicate_pad_numbers_are_jumpers no)
		(fp_line
			(start -0.7874 -0.4064)
			(end -0.7874 0.4064)
			(stroke
				(width 0.1524)
				(type default)
			)
			(layer "B.SilkS")
		)
		(fp_line
			(start -0.7874 0.4064)
			(end 0.7874 0.4064)
			(stroke
				(width 0.1524)
				(type default)
			)
			(layer "B.SilkS")
		)
		(fp_line
			(start 0.7874 -0.4064)
			(end -0.7874 -0.4064)
			(stroke
				(width 0.1524)
				(type default)
			)
			(layer "B.SilkS")
		)
		(fp_line
			(start 0.7874 0.4064)
			(end 0.7874 -0.4064)
			(stroke
				(width 0.1524)
				(type default)
			)
			(layer "B.SilkS")
		)
		(fp_line
			(start -0.67945 -0.3048)
			(end -0.67945 0.3048)
			(stroke
				(width 0.1)
				(type default)
			)
			(layer "B.Fab")
		)
		(fp_line
			(start -0.67945 0.3048)
			(end -0.120396 0.3048)
			(stroke
				(width 0.1)
				(type default)
			)
			(layer "B.Fab")
		)
		(fp_line
			(start -0.12065 -0.3048)
			(end -0.67945 -0.3048)
			(stroke
				(width 0.1)
				(type default)
			)
			(layer "B.Fab")
		)
		(fp_line
			(start -0.12065 -0.2794)
			(end -0.12065 -0.3048)
			(stroke
				(width 0.1)
				(type default)
			)
			(layer "B.Fab")
		)
		(fp_line
			(start -0.120396 0.2794)
			(end 0.12065 0.2794)
			(stroke
				(width 0.1)
				(type default)
			)
			(layer "B.Fab")
		)
		(fp_line
			(start -0.120396 0.3048)
			(end -0.120396 0.2794)
			(stroke
				(width 0.1)
				(type default)
			)
			(layer "B.Fab")
		)
		(fp_line
			(start 0.12065 -0.305054)
			(end 0.12065 -0.2794)
			(stroke
				(width 0.1)
				(type default)
			)
			(layer "B.Fab")
		)
		(fp_line
			(start 0.12065 -0.2794)
			(end -0.12065 -0.2794)
			(stroke
				(width 0.1)
				(type default)
			)
			(layer "B.Fab")
		)
		(fp_line
			(start 0.12065 0.2794)
			(end 0.12065 0.3048)
			(stroke
				(width 0.1)
				(type default)
			)
			(layer "B.Fab")
		)
		(fp_line
			(start 0.12065 0.3048)
			(end 0.67945 0.3048)
			(stroke
				(width 0.1)
				(type default)
			)
			(layer "B.Fab")
		)
		(fp_line
			(start 0.67945 -0.305054)
			(end 0.12065 -0.305054)
			(stroke
				(width 0.1)
				(type default)
			)
			(layer "B.Fab")
		)
		(fp_line
			(start 0.67945 0.3048)
			(end 0.67945 -0.305054)
			(stroke
				(width 0.1)
				(type default)
			)
			(layer "B.Fab")
		)
		(pad "1" smd circle
			(at 0.40005 0 180)
			(size 0 0)
			(layers "B.Cu" "B.Mask" "B.Paste")
			(net "PVDDCR_SOC_P0")
		)
		(pad "2" smd circle
			(at -0.40005 0 180)
			(size 0 0)
			(layers "B.Cu" "B.Mask" "B.Paste")
			(net "GND")
		)
	)
	(footprint ""
		(layer "B.Cu")
		(at 431.55616 -192.660016)
		(property "Reference" "C163"
			(at 0 0 0)
			(layer "B.SilkS")
			(hide yes)
			(effects
				(font
					(size 1.27 1.27)
				)
				(justify mirror)
			)
		)
		(property "Value" ""
			(at 0 0 0)
			(layer "B.Fab")
			(effects
				(font
					(size 1.27 1.27)
				)
				(justify mirror)
			)
		)
		(duplicate_pad_numbers_are_jumpers no)
		(fp_line
			(start -1.524 -0.762)
			(end -1.524 0.762)
			(stroke
				(width 0.1524)
				(type default)
			)
			(layer "B.SilkS")
		)
		(fp_line
			(start -1.524 0.762)
			(end 1.524 0.762)
			(stroke
				(width 0.1524)
				(type default)
			)
			(layer "B.SilkS")
		)
		(fp_line
			(start 1.524 -0.762)
			(end -1.524 -0.762)
			(stroke
				(width 0.1524)
				(type default)
			)
			(layer "B.SilkS")
		)
		(fp_line
			(start 1.524 0.762)
			(end 1.524 -0.762)
			(stroke
				(width 0.1524)
				(type default)
			)
			(layer "B.SilkS")
		)
		(fp_line
			(start -1.1049 -0.724916)
			(end 1.1049 -0.724916)
			(stroke
				(width 0.1)
				(type default)
			)
			(layer "B.Fab")
		)
		(fp_line
			(start -1.1049 0.724916)
			(end -1.1049 -0.724916)
			(stroke
				(width 0.1)
				(type default)
			)
			(layer "B.Fab")
		)
		(fp_line
			(start 1.1049 -0.724916)
			(end 1.1049 0.724916)
			(stroke
				(width 0.1)
				(type default)
			)
			(layer "B.Fab")
		)
		(fp_line
			(start 1.1049 0.724916)
			(end -1.1049 0.724916)
			(stroke
				(width 0.1)
				(type default)
			)
			(layer "B.Fab")
		)
		(pad "1" smd rect
			(at 0.889 0)
			(size 1.016 1.27)
			(layers "B.Cu" "B.Mask" "B.Paste")
			(net "P12V_MEM_CPU0")
		)
		(pad "2" smd rect
			(at -0.889 0)
			(size 1.016 1.27)
			(layers "B.Cu" "B.Mask" "B.Paste")
			(net "GND")
		)
	)
	(footprint ""
		(layer "B.Cu")
		(at 172.312838 -418.190426)
		(property "Reference" "R2812"
			(at 0 0 0)
			(layer "B.SilkS")
			(hide yes)
			(effects
				(font
					(size 1.27 1.27)
				)
				(justify mirror)
			)
		)
		(property "Value" ""
			(at 0 0 0)
			(layer "B.Fab")
			(effects
				(font
					(size 1.27 1.27)
				)
				(justify mirror)
			)
		)
		(duplicate_pad_numbers_are_jumpers no)
		(fp_line
			(start -0.7874 -0.4064)
			(end -0.7874 0.4064)
			(stroke
				(width 0.1524)
				(type default)
			)
			(layer "B.SilkS")
		)
		(fp_line
			(start -0.7874 0.4064)
			(end 0.7874 0.4064)
			(stroke
				(width 0.1524)
				(type default)
			)
			(layer "B.SilkS")
		)
		(fp_line
			(start 0.7874 -0.4064)
			(end -0.7874 -0.4064)
			(stroke
				(width 0.1524)
				(type default)
			)
			(layer "B.SilkS")
		)
		(fp_line
			(start 0.7874 0.4064)
			(end 0.7874 -0.4064)
			(stroke
				(width 0.1524)
				(type default)
			)
			(layer "B.SilkS")
		)
		(fp_line
			(start -0.67945 -0.3048)
			(end -0.67945 0.3048)
			(stroke
				(width 0.1)
				(type default)
			)
			(layer "B.Fab")
		)
		(fp_line
			(start -0.67945 0.3048)
			(end -0.120396 0.3048)
			(stroke
				(width 0.1)
				(type default)
			)
			(layer "B.Fab")
		)
		(fp_line
			(start -0.12065 -0.3048)
			(end -0.67945 -0.3048)
			(stroke
				(width 0.1)
				(type default)
			)
			(layer "B.Fab")
		)
		(fp_line
			(start -0.12065 -0.2794)
			(end -0.12065 -0.3048)
			(stroke
				(width 0.1)
				(type default)
			)
			(layer "B.Fab")
		)
		(fp_line
			(start -0.120396 0.2794)
			(end 0.12065 0.2794)
			(stroke
				(width 0.1)
				(type default)
			)
			(layer "B.Fab")
		)
		(fp_line
			(start -0.120396 0.3048)
			(end -0.120396 0.2794)
			(stroke
				(width 0.1)
				(type default)
			)
			(layer "B.Fab")
		)
		(fp_line
			(start 0.12065 -0.305054)
			(end 0.12065 -0.2794)
			(stroke
				(width 0.1)
				(type default)
			)
			(layer "B.Fab")
		)
		(fp_line
			(start 0.12065 -0.2794)
			(end -0.12065 -0.2794)
			(stroke
				(width 0.1)
				(type default)
			)
			(layer "B.Fab")
		)
		(fp_line
			(start 0.12065 0.2794)
			(end 0.12065 0.3048)
			(stroke
				(width 0.1)
				(type default)
			)
			(layer "B.Fab")
		)
		(fp_line
			(start 0.12065 0.3048)
			(end 0.67945 0.3048)
			(stroke
				(width 0.1)
				(type default)
			)
			(layer "B.Fab")
		)
		(fp_line
			(start 0.67945 -0.305054)
			(end 0.12065 -0.305054)
			(stroke
				(width 0.1)
				(type default)
			)
			(layer "B.Fab")
		)
		(fp_line
			(start 0.67945 0.3048)
			(end 0.67945 -0.305054)
			(stroke
				(width 0.1)
				(type default)
			)
			(layer "B.Fab")
		)
		(pad "1" smd circle
			(at 0.40005 0 180)
			(size 0 0)
			(layers "B.Cu" "B.Mask" "B.Paste")
			(net "SMB_FAN_3V3AUX_BUF_SDA")
		)
		(pad "2" smd circle
			(at -0.40005 0 180)
			(size 0 0)
			(layers "B.Cu" "B.Mask" "B.Paste")
			(net "SMB_FAN_3V3AUX_BUF_R_SDA")
		)
	)
	(footprint ""
		(layer "B.Cu")
		(at 250.07697 -45.461682 90)
		(property "Reference" "R3958"
			(at 0 0 90)
			(layer "B.SilkS")
			(hide yes)
			(effects
				(font
					(size 1.27 1.27)
				)
				(justify mirror)
			)
		)
		(property "Value" ""
			(at 0 0 90)
			(layer "B.Fab")
			(effects
				(font
					(size 1.27 1.27)
				)
				(justify mirror)
			)
		)
		(duplicate_pad_numbers_are_jumpers no)
		(fp_line
			(start 0.7874 -0.4064)
			(end -0.7874 -0.4064)
			(stroke
				(width 0.1524)
				(type default)
			)
			(layer "B.SilkS")
		)
		(fp_line
			(start -0.7874 -0.4064)
			(end -0.7874 0.4064)
			(stroke
				(width 0.1524)
				(type default)
			)
			(layer "B.SilkS")
		)
		(fp_line
			(start 0.7874 0.4064)
			(end 0.7874 -0.4064)
			(stroke
				(width 0.1524)
				(type default)
			)
			(layer "B.SilkS")
		)
		(fp_line
			(start -0.7874 0.4064)
			(end 0.7874 0.4064)
			(stroke
				(width 0.1524)
				(type default)
			)
			(layer "B.SilkS")
		)
		(fp_line
			(start 0.67945 -0.305054)
			(end 0.12065 -0.305054)
			(stroke
				(width 0.1)
				(type default)
			)
			(layer "B.Fab")
		)
		(fp_line
			(start 0.12065 -0.305054)
			(end 0.12065 -0.2794)
			(stroke
				(width 0.1)
				(type default)
			)
			(layer "B.Fab")
		)
		(fp_line
			(start -0.12065 -0.3048)
			(end -0.67945 -0.3048)
			(stroke
				(width 0.1)
				(type default)
			)
			(layer "B.Fab")
		)
		(fp_line
			(start -0.67945 -0.3048)
			(end -0.67945 0.3048)
			(stroke
				(width 0.1)
				(type default)
			)
			(layer "B.Fab")
		)
		(fp_line
			(start 0.12065 -0.2794)
			(end -0.12065 -0.2794)
			(stroke
				(width 0.1)
				(type default)
			)
			(layer "B.Fab")
		)
		(fp_line
			(start -0.12065 -0.2794)
			(end -0.12065 -0.3048)
			(stroke
				(width 0.1)
				(type default)
			)
			(layer "B.Fab")
		)
		(fp_line
			(start 0.12065 0.2794)
			(end 0.12065 0.3048)
			(stroke
				(width 0.1)
				(type default)
			)
			(layer "B.Fab")
		)
		(fp_line
			(start -0.120396 0.2794)
			(end 0.12065 0.2794)
			(stroke
				(width 0.1)
				(type default)
			)
			(layer "B.Fab")
		)
		(fp_line
			(start 0.67945 0.3048)
			(end 0.67945 -0.305054)
			(stroke
				(width 0.1)
				(type default)
			)
			(layer "B.Fab")
		)
		(fp_line
			(start 0.12065 0.3048)
			(end 0.67945 0.3048)
			(stroke
				(width 0.1)
				(type default)
			)
			(layer "B.Fab")
		)
		(fp_line
			(start -0.120396 0.3048)
			(end -0.120396 0.2794)
			(stroke
				(width 0.1)
				(type default)
			)
			(layer "B.Fab")
		)
		(fp_line
			(start -0.67945 0.3048)
			(end -0.120396 0.3048)
			(stroke
				(width 0.1)
				(type default)
			)
			(layer "B.Fab")
		)
		(pad "1" smd circle
			(at 0.40005 0 270)
			(size 0 0)
			(layers "B.Cu" "B.Mask" "B.Paste")
			(net "P12V_E1S_UV_0_R")
		)
		(pad "2" smd circle
			(at -0.40005 0 270)
			(size 0 0)
			(layers "B.Cu" "B.Mask" "B.Paste")
			(net "P12V_E1S_UV_0")
		)
	)
)
